M48
INCH,TZ
T01C.01
T02C.012
T03C.01456
T04C.016
T05C.02244
T06C.029
T07C.031
T08C.032
T09C.034
T010C.035
T011C.036
T012C.038
T013C.039
T014C.04
T015C.042
T016C.045
T017C.048
T018C.05
T019C.051
T020C.053
T021C.061
T022C.062
T023C.086
T024C.087
T025C.091
T026C.093
T027C.099
T028C.126
T029C.128
T030C.138
T031C.14
T032C.199
T033C.276
;EXTENTS: -10.000 -19.627 45.000  30.373  
;LEADER: 12 
;HEADER: 
;CODE  : ASCII 
;FILE  : 13948-1b.rou for board 13948-1b.brd
%
G90
F1
M16
T028
M16
G00X1224015Y411417
G40
M15
G01X1230315
M16
G00X1005118
G40
M15
G01X1011418
M16
G00X1005118Y244094
G40
M15
G01X1011418
M16
G00X1224016Y155511
G40
M15
G01X1230316
M16
G40
M30
